# SCM (Grand Teton) — schematic netlist excerpt (pin names and nets, part order shuffled) for the footprints in the layout excerpt that follows; sources: Cadence DE-HDL packaged netlist, KiCad conversion of 12092022_DA0F0TMDCD0_F0T_Management_Board_D_brd_V3_OCP.brd

R230  Q_RES  10K 1% CHIP  pkg 0402LF  page 32 : A = P3V3_AUX ; B = JTAG_MB_TDO
C108  Q_CAP  1UF 25V 10% X6S  pkg C0402  page 16 : A = P1V0_AUX ; B = GND

(kicad_pcb
	(version 20260206)
	(generator "pcbnew")
	(generator_version "10.0")
	(general
		(thickness 1.6)
		(legacy_teardrops no)
	)
	(paper "A4")
	(title_block
		(title "12092022_DA0F0TMDCD0_F0T_Management_Board_D_brd_V3_OCP.brd")
		(comment 1 "Grand Teton / footprints 1189-1190 of 1440")
	)
	(layers
		(0 "F.Cu" signal "TOP")
		(4 "In1.Cu" signal "GND")
		(6 "In2.Cu" signal "IN1")
		(8 "In3.Cu" signal "GND1")
		(10 "In4.Cu" signal "IN2")
		(12 "In5.Cu" signal "VCC")
		(14 "In6.Cu" signal "VCC1")
		(16 "In7.Cu" signal "IN3")
		(18 "In8.Cu" signal "GND2")
		(20 "In9.Cu" signal "IN4")
		(22 "In10.Cu" signal "GND3")
		(2 "B.Cu" signal "BOTTOM")
		(9 "F.Adhes" user "F.Adhesive")
		(11 "B.Adhes" user "B.Adhesive")
		(13 "F.Paste" user "Package Geometry/Pastemask Top")
		(15 "B.Paste" user "Package Geometry/Pastemask Bottom")
		(5 "F.SilkS" user "Ref Des/Silkscreen Top")
		(7 "B.SilkS" user "Ref Des/Silkscreen Bottom")
		(1 "F.Mask" user "Board Geometry/Soldermask Top")
		(3 "B.Mask" user "Board Geometry/Soldermask Bottom")
		(17 "Dwgs.User" user "User.Drawings")
		(19 "Cmts.User" user "User.Comments")
		(21 "Eco1.User" user "User.Eco1")
		(23 "Eco2.User" user "User.Eco2")
		(25 "Edge.Cuts" user "Board Geometry/Outline")
		(27 "Margin" user)
		(31 "F.CrtYd" user "Package Geometry/Place Bound Top")
		(29 "B.CrtYd" user "Package Geometry/Place Bound Bottom")
		(35 "F.Fab" user "Ref Des/Assembly Top")
		(33 "B.Fab" user "Ref Des/Assembly Bottom")
	)
	(footprint ""
		(layer "B.Cu")
		(at 35.052 -106.3625 -90)
		(property "Reference" "R230"
			(at 0 0 90)
			(layer "B.SilkS")
			(hide yes)
			(effects
				(font
					(size 1.27 1.27)
				)
				(justify mirror)
			)
		)
		(property "Value" ""
			(at 0 0 90)
			(layer "B.Fab")
			(effects
				(font
					(size 1.27 1.27)
				)
				(justify mirror)
			)
		)
		(duplicate_pad_numbers_are_jumpers no)
		(fp_line
			(start -0.7874 0.4064)
			(end 0.7874 0.4064)
			(stroke
				(width 0.1524)
				(type default)
			)
			(layer "B.SilkS")
		)
		(fp_line
			(start 0.7874 0.4064)
			(end 0.7874 -0.4064)
			(stroke
				(width 0.1524)
				(type default)
			)
			(layer "B.SilkS")
		)
		(fp_line
			(start -0.7874 -0.4064)
			(end -0.7874 0.4064)
			(stroke
				(width 0.1524)
				(type default)
			)
			(layer "B.SilkS")
		)
		(fp_line
			(start 0.7874 -0.4064)
			(end -0.7874 -0.4064)
			(stroke
				(width 0.1524)
				(type default)
			)
			(layer "B.SilkS")
		)
		(fp_line
			(start -0.67945 0.3048)
			(end -0.120396 0.3048)
			(stroke
				(width 0.1)
				(type default)
			)
			(layer "B.Fab")
		)
		(fp_line
			(start -0.120396 0.3048)
			(end -0.120396 0.2794)
			(stroke
				(width 0.1)
				(type default)
			)
			(layer "B.Fab")
		)
		(fp_line
			(start 0.12065 0.3048)
			(end 0.67945 0.3048)
			(stroke
				(width 0.1)
				(type default)
			)
			(layer "B.Fab")
		)
		(fp_line
			(start 0.67945 0.3048)
			(end 0.67945 -0.305054)
			(stroke
				(width 0.1)
				(type default)
			)
			(layer "B.Fab")
		)
		(fp_line
			(start -0.120396 0.2794)
			(end 0.12065 0.2794)
			(stroke
				(width 0.1)
				(type default)
			)
			(layer "B.Fab")
		)
		(fp_line
			(start 0.12065 0.2794)
			(end 0.12065 0.3048)
			(stroke
				(width 0.1)
				(type default)
			)
			(layer "B.Fab")
		)
		(fp_line
			(start -0.12065 -0.2794)
			(end -0.12065 -0.3048)
			(stroke
				(width 0.1)
				(type default)
			)
			(layer "B.Fab")
		)
		(fp_line
			(start 0.12065 -0.2794)
			(end -0.12065 -0.2794)
			(stroke
				(width 0.1)
				(type default)
			)
			(layer "B.Fab")
		)
		(fp_line
			(start -0.67945 -0.3048)
			(end -0.67945 0.3048)
			(stroke
				(width 0.1)
				(type default)
			)
			(layer "B.Fab")
		)
		(fp_line
			(start -0.12065 -0.3048)
			(end -0.67945 -0.3048)
			(stroke
				(width 0.1)
				(type default)
			)
			(layer "B.Fab")
		)
		(fp_line
			(start 0.12065 -0.305054)
			(end 0.12065 -0.2794)
			(stroke
				(width 0.1)
				(type default)
			)
			(layer "B.Fab")
		)
		(fp_line
			(start 0.67945 -0.305054)
			(end 0.12065 -0.305054)
			(stroke
				(width 0.1)
				(type default)
			)
			(layer "B.Fab")
		)
		(pad "1" smd circle
			(at 0.40005 0 90)
			(size 0 0)
			(layers "B.Cu" "B.Mask" "B.Paste")
			(net "P3V3_AUX")
		)
		(pad "2" smd circle
			(at -0.40005 0 90)
			(size 0 0)
			(layers "B.Cu" "B.Mask" "B.Paste")
			(net "JTAG_MB_TDO")
		)
	)
	(footprint ""
		(layer "B.Cu")
		(at 72.799194 -55.399686 90)
		(property "Reference" "C108"
			(at 0 0 90)
			(layer "B.SilkS")
			(hide yes)
			(effects
				(font
					(size 1.27 1.27)
				)
				(justify mirror)
			)
		)
		(property "Value" ""
			(at 0 0 90)
			(layer "B.Fab")
			(effects
				(font
					(size 1.27 1.27)
				)
				(justify mirror)
			)
		)
		(duplicate_pad_numbers_are_jumpers no)
		(fp_line
			(start 0.7874 -0.4064)
			(end -0.7874 -0.4064)
			(stroke
				(width 0.1524)
				(type default)
			)
			(layer "B.SilkS")
		)
		(fp_line
			(start -0.7874 -0.4064)
			(end -0.7874 0.4064)
			(stroke
				(width 0.1524)
				(type default)
			)
			(layer "B.SilkS")
		)
		(fp_line
			(start 0.7874 0.4064)
			(end 0.7874 -0.4064)
			(stroke
				(width 0.1524)
				(type default)
			)
			(layer "B.SilkS")
		)
		(fp_line
			(start -0.7874 0.4064)
			(end 0.7874 0.4064)
			(stroke
				(width 0.1524)
				(type default)
			)
			(layer "B.SilkS")
		)
		(fp_line
			(start 0.67945 -0.305054)
			(end 0.12065 -0.305054)
			(stroke
				(width 0.1)
				(type default)
			)
			(layer "B.Fab")
		)
		(fp_line
			(start 0.12065 -0.305054)
			(end 0.12065 -0.2794)
			(stroke
				(width 0.1)
				(type default)
			)
			(layer "B.Fab")
		)
		(fp_line
			(start -0.12065 -0.3048)
			(end -0.67945 -0.3048)
			(stroke
				(width 0.1)
				(type default)
			)
			(layer "B.Fab")
		)
		(fp_line
			(start -0.67945 -0.3048)
			(end -0.67945 0.3048)
			(stroke
				(width 0.1)
				(type default)
			)
			(layer "B.Fab")
		)
		(fp_line
			(start 0.12065 -0.2794)
			(end -0.12065 -0.2794)
			(stroke
				(width 0.1)
				(type default)
			)
			(layer "B.Fab")
		)
		(fp_line
			(start -0.12065 -0.2794)
			(end -0.12065 -0.3048)
			(stroke
				(width 0.1)
				(type default)
			)
			(layer "B.Fab")
		)
		(fp_line
			(start 0.12065 0.2794)
			(end 0.12065 0.3048)
			(stroke
				(width 0.1)
				(type default)
			)
			(layer "B.Fab")
		)
		(fp_line
			(start -0.120396 0.2794)
			(end 0.12065 0.2794)
			(stroke
				(width 0.1)
				(type default)
			)
			(layer "B.Fab")
		)
		(fp_line
			(start 0.67945 0.3048)
			(end 0.67945 -0.305054)
			(stroke
				(width 0.1)
				(type default)
			)
			(layer "B.Fab")
		)
		(fp_line
			(start 0.12065 0.3048)
			(end 0.67945 0.3048)
			(stroke
				(width 0.1)
				(type default)
			)
			(layer "B.Fab")
		)
		(fp_line
			(start -0.120396 0.3048)
			(end -0.120396 0.2794)
			(stroke
				(width 0.1)
				(type default)
			)
			(layer "B.Fab")
		)
		(fp_line
			(start -0.67945 0.3048)
			(end -0.120396 0.3048)
			(stroke
				(width 0.1)
				(type default)
			)
			(layer "B.Fab")
		)
		(pad "1" smd circle
			(at 0.40005 0 270)
			(size 0 0)
			(layers "B.Cu" "B.Mask" "B.Paste")
			(net "P1V0_AUX")
		)
		(pad "2" smd circle
			(at -0.40005 0 270)
			(size 0 0)
			(layers "B.Cu" "B.Mask" "B.Paste")
			(net "GND")
		)
	)
)
